G04 ================== begin FILE IDENTIFICATION RECORD ==================*
G04 Layout Name:  9051_F0T_Panel_BD_Front_D_v02_20221209_1310.brd*
G04 Film Name:    smb.art*
G04 File Format:  Gerber RS274X*
G04 File Origin:  Cadence Allegro 17.2-S081*
G04 Origin Date:  Mon Dec 12 15:51:17 2022*
G04 *
G04 Layer:  DRAWING FORMAT/TITLE_BLOCK_A*
G04 Layer:  DRAWING FORMAT/TITLE_BLOCK*
G04 Layer:  VIA CLASS/SOLDERMASK_BOTTOM*
G04 Layer:  PIN/SOLDERMASK_BOTTOM*
G04 Layer:  PACKAGE GEOMETRY/SOLDERMASK_BOTTOM*
G04 Layer:  MANUFACTURING/PHOTOPLOT_OUTLINE*
G04 Layer:  DRAWING FORMAT/TITLE_DATA_SMB*
G04 Layer:  BOARD GEOMETRY/SOLDERMASK_BOTTOM*
G04 *
G04 Offset:    (0.00 0.00)*
G04 Mirror:    No*
G04 Mode:      Positive*
G04 Rotation:  0*
G04 FullContactRelief:  No*
G04 UndefLineWidth:     6.00*
G04 ================== end FILE IDENTIFICATION RECORD ====================*
%FSLAX25Y25*MOIN*%
%IR0*IPPOS*OFA0.00000B0.00000*MIA0B0*SFA1.00000B1.00000*%
%ADD21O,.056X.107*%
%ADD12C,.03*%
%ADD26C,.061*%
%ADD14C,.052*%
%ADD11C,.034*%
%ADD19C,.072*%
%ADD20C,.046*%
%ADD22C,.048*%
%ADD25C,.085*%
%ADD17C,.058*%
%ADD10R,.052X.052*%
%ADD27C,.0395*%
%ADD24R,.048X.048*%
%ADD28C,.0785*%
%ADD18R,.058X.058*%
%ADD13C,.145*%
%ADD16C,.139*%
%ADD23O,.056X.079*%
%ADD15C,.178*%
%ADD29C,.02*%
%ADD30C,.006*%
%ADD31C,.1942*%
G75*
%LPD*%
G75*
G36*
G01X43901Y58661D02*
G02X4131I-19885J0D01*
G01Y72441D01*
G02X43901I19885J0D01*
G01Y58661D01*
G37*
G36*
G01X41932Y279449D02*
G02X10036I-15948J0D01*
G01Y293229D01*
G02X41932I15948J0D01*
G01Y279449D01*
G37*
G36*
G01X152169Y43425D02*
G02X120273I-15948J0D01*
G01Y57205D01*
G02X152169I15948J0D01*
G01Y43425D01*
G37*
G36*
G01X149019Y247543D02*
G02X109249I-19885J0D01*
G01Y261323D01*
G02X149019I19885J0D01*
G01Y247543D01*
G37*
%LPC*%
G75*
G36*
G01X16921Y285904D02*
G02X35047I9063J7324D01*
G03X33700Y282093I4716J-3811D01*
G01Y279449D01*
G02X18268I-7716J0D01*
G01Y282093D01*
G03X16921Y285904I-6065J0D01*
G37*
G36*
G01X127158Y49880D02*
G02X145284I9063J7324D01*
G03X143937Y46069I4716J-3811D01*
G01Y43425D01*
G02X128505I-7716J0D01*
G01Y46069D01*
G03X127158Y49880I-6065J0D01*
G37*
G54D31*
X24016Y58661D03*
X129134Y247543D03*
%LPD*%
G75*
G54D10*
X10315Y20079D03*
X33937D03*
G54D20*
X61516Y326772D03*
Y314961D03*
X110532Y326772D03*
Y314961D03*
G54D11*
X13553Y48198D03*
Y69124D03*
X9218Y58661D03*
X34479Y48198D03*
X24016Y43863D03*
X34479Y69124D03*
X24016Y73459D03*
X38814Y58661D03*
X118671Y237080D03*
Y258006D03*
X114336Y247543D03*
X139597Y237080D03*
X129134Y232745D03*
Y262341D03*
X139597Y258006D03*
X143932Y247543D03*
G54D30*
G01X-117168Y-317735D02*
Y-322735D01*
G01X-118625Y-317735D02*
X-115711D01*
G01X-110801Y-322735D02*
X-113335D01*
Y-317735D01*
X-110801D01*
G01X-111815Y-320152D02*
X-113335D01*
G01X-108235Y-317735D02*
Y-322735D01*
X-105701D01*
G01X-101868Y-322902D02*
X-101995Y-322818D01*
Y-322652D01*
X-101868Y-322568D01*
X-101741Y-322652D01*
Y-322818D01*
X-101868Y-322902D01*
G01Y-320652D02*
X-101995Y-320568D01*
Y-320402D01*
X-101868Y-320318D01*
X-101741Y-320402D01*
Y-320568D01*
X-101868Y-320652D01*
G01X-97085Y-324402D02*
X-97718Y-323568D01*
X-98035Y-322735D01*
Y-319402D01*
X-97718Y-318568D01*
X-97085Y-317735D01*
G01X-91668D02*
X-92175Y-317902D01*
X-92555Y-318318D01*
X-92808Y-318818D01*
X-92998Y-319485D01*
X-93061Y-320235D01*
X-92998Y-320985D01*
X-92808Y-321652D01*
X-92555Y-322152D01*
X-92175Y-322568D01*
X-91668Y-322735D01*
X-91161Y-322568D01*
X-90781Y-322152D01*
X-90528Y-321652D01*
X-90338Y-320985D01*
X-90275Y-320235D01*
X-90338Y-319485D01*
X-90528Y-318818D01*
X-90781Y-318318D01*
X-91161Y-317902D01*
X-91668Y-317735D01*
G01X-87961Y-321735D02*
X-87581Y-322318D01*
X-87075Y-322652D01*
X-86505Y-322735D01*
X-85998Y-322652D01*
X-85491Y-322235D01*
X-85175Y-321735D01*
X-85111Y-321235D01*
X-85238Y-320652D01*
X-85681Y-320235D01*
X-86125Y-320068D01*
X-86695D01*
G01X-86125D02*
X-85745Y-319818D01*
X-85428Y-319402D01*
X-85301Y-318902D01*
X-85428Y-318402D01*
X-85745Y-317985D01*
X-86315Y-317735D01*
X-86885Y-317818D01*
X-87455Y-318152D01*
G01X-81151Y-324402D02*
X-80518Y-323568D01*
X-80201Y-322735D01*
Y-319402D01*
X-80518Y-318568D01*
X-81151Y-317735D01*
G01X-77761Y-321735D02*
X-77381Y-322318D01*
X-76875Y-322652D01*
X-76305Y-322735D01*
X-75798Y-322652D01*
X-75291Y-322235D01*
X-74975Y-321735D01*
X-74911Y-321235D01*
X-75038Y-320652D01*
X-75481Y-320235D01*
X-75925Y-320068D01*
X-76495D01*
G01X-75925D02*
X-75545Y-319818D01*
X-75228Y-319402D01*
X-75101Y-318902D01*
X-75228Y-318402D01*
X-75545Y-317985D01*
X-76115Y-317735D01*
X-76685Y-317818D01*
X-77255Y-318152D01*
G01X-72471Y-318568D02*
X-72091Y-318068D01*
X-71648Y-317818D01*
X-71141Y-317735D01*
X-70508Y-317902D01*
X-70065Y-318318D01*
X-69938Y-318818D01*
X-70001Y-319318D01*
X-70255Y-319735D01*
X-71521Y-320568D01*
X-72091Y-321152D01*
X-72471Y-321985D01*
X-72598Y-322735D01*
X-69938D01*
G01X-66295D02*
X-66168Y-321652D01*
X-65978Y-320735D01*
X-65725Y-319902D01*
X-65408Y-318985D01*
X-64901Y-317735D01*
X-67435D01*
G01X-61891Y-321068D02*
X-60245D01*
G01X-57171Y-318568D02*
X-56791Y-318068D01*
X-56348Y-317818D01*
X-55841Y-317735D01*
X-55208Y-317902D01*
X-54765Y-318318D01*
X-54638Y-318818D01*
X-54701Y-319318D01*
X-54955Y-319735D01*
X-56221Y-320568D01*
X-56791Y-321152D01*
X-57171Y-321985D01*
X-57298Y-322735D01*
X-54638D01*
G01X-52261Y-321735D02*
X-51881Y-322318D01*
X-51375Y-322652D01*
X-50805Y-322735D01*
X-50298Y-322652D01*
X-49791Y-322235D01*
X-49475Y-321735D01*
X-49411Y-321235D01*
X-49538Y-320652D01*
X-49981Y-320235D01*
X-50425Y-320068D01*
X-50995D01*
G01X-50425D02*
X-50045Y-319818D01*
X-49728Y-319402D01*
X-49601Y-318902D01*
X-49728Y-318402D01*
X-50045Y-317985D01*
X-50615Y-317735D01*
X-51185Y-317818D01*
X-51755Y-318152D01*
G01X-45008Y-322735D02*
Y-317735D01*
X-47351Y-321318D01*
X-44185D01*
G01X-42061Y-321985D02*
X-41681Y-322402D01*
X-41238Y-322652D01*
X-40668Y-322735D01*
X-40098Y-322568D01*
X-39655Y-322235D01*
X-39338Y-321652D01*
X-39275Y-320985D01*
X-39401Y-320318D01*
X-39718Y-319902D01*
X-40161Y-319568D01*
X-40605Y-319485D01*
X-41048Y-319568D01*
X-41618Y-319902D01*
X-41428Y-317735D01*
X-39718D01*
G01X-31671Y-322735D02*
Y-317735D01*
X-29265D01*
G01X-30151Y-320152D02*
X-31671D01*
G01X-26951Y-322735D02*
X-25368Y-317735D01*
X-23785Y-322735D01*
G01X-24355Y-320985D02*
X-26381D01*
G01X-21598Y-322735D02*
X-18938Y-317735D01*
G01X-21598D02*
X-18938Y-322735D01*
G01X-15168Y-322902D02*
X-15295Y-322818D01*
Y-322652D01*
X-15168Y-322568D01*
X-15041Y-322652D01*
Y-322818D01*
X-15168Y-322902D01*
G01Y-320652D02*
X-15295Y-320568D01*
Y-320402D01*
X-15168Y-320318D01*
X-15041Y-320402D01*
Y-320568D01*
X-15168Y-320652D01*
G01X-10385Y-324402D02*
X-11018Y-323568D01*
X-11335Y-322735D01*
Y-319402D01*
X-11018Y-318568D01*
X-10385Y-317735D01*
G01X-4968D02*
X-5475Y-317902D01*
X-5855Y-318318D01*
X-6108Y-318818D01*
X-6298Y-319485D01*
X-6361Y-320235D01*
X-6298Y-320985D01*
X-6108Y-321652D01*
X-5855Y-322152D01*
X-5475Y-322568D01*
X-4968Y-322735D01*
X-4461Y-322568D01*
X-4081Y-322152D01*
X-3828Y-321652D01*
X-3638Y-320985D01*
X-3575Y-320235D01*
X-3638Y-319485D01*
X-3828Y-318818D01*
X-4081Y-318318D01*
X-4461Y-317902D01*
X-4968Y-317735D01*
G01X-1261Y-321735D02*
X-881Y-322318D01*
X-375Y-322652D01*
X195Y-322735D01*
X702Y-322652D01*
X1209Y-322235D01*
X1525Y-321735D01*
X1589Y-321235D01*
X1462Y-320652D01*
X1019Y-320235D01*
X575Y-320068D01*
X5D01*
G01X575D02*
X955Y-319818D01*
X1272Y-319402D01*
X1399Y-318902D01*
X1272Y-318402D01*
X955Y-317985D01*
X385Y-317735D01*
X-185Y-317818D01*
X-755Y-318152D01*
G01X5549Y-324402D02*
X6182Y-323568D01*
X6499Y-322735D01*
Y-319402D01*
X6182Y-318568D01*
X5549Y-317735D01*
G01X8939Y-321735D02*
X9319Y-322318D01*
X9825Y-322652D01*
X10395Y-322735D01*
X10902Y-322652D01*
X11409Y-322235D01*
X11725Y-321735D01*
X11789Y-321235D01*
X11662Y-320652D01*
X11219Y-320235D01*
X10775Y-320068D01*
X10205D01*
G01X10775D02*
X11155Y-319818D01*
X11472Y-319402D01*
X11599Y-318902D01*
X11472Y-318402D01*
X11155Y-317985D01*
X10585Y-317735D01*
X10015Y-317818D01*
X9445Y-318152D01*
G01X14355Y-322152D02*
X14799Y-322568D01*
X15305Y-322735D01*
X15812Y-322568D01*
X16255Y-322068D01*
X16572Y-321318D01*
X16699Y-320568D01*
Y-319652D01*
X16572Y-318902D01*
X16255Y-318235D01*
X15875Y-317902D01*
X15432Y-317735D01*
X14925Y-317902D01*
X14545Y-318235D01*
X14292Y-318735D01*
X14165Y-319402D01*
X14292Y-319985D01*
X14609Y-320568D01*
X14989Y-320902D01*
X15432Y-320985D01*
X15939Y-320818D01*
X16319Y-320402D01*
X16699Y-319652D01*
G01X20405Y-322735D02*
X20532Y-321652D01*
X20722Y-320735D01*
X20975Y-319902D01*
X21292Y-318985D01*
X21799Y-317735D01*
X19265D01*
G01X24809Y-321068D02*
X26455D01*
G01X29339Y-321735D02*
X29719Y-322318D01*
X30225Y-322652D01*
X30795Y-322735D01*
X31302Y-322652D01*
X31809Y-322235D01*
X32125Y-321735D01*
X32189Y-321235D01*
X32062Y-320652D01*
X31619Y-320235D01*
X31175Y-320068D01*
X30605D01*
G01X31175D02*
X31555Y-319818D01*
X31872Y-319402D01*
X31999Y-318902D01*
X31872Y-318402D01*
X31555Y-317985D01*
X30985Y-317735D01*
X30415Y-317818D01*
X29845Y-318152D01*
G01X34629Y-320652D02*
X35072Y-320068D01*
X35452Y-319735D01*
X35959Y-319568D01*
X36402Y-319735D01*
X36719Y-320068D01*
X36972Y-320568D01*
X37035Y-321152D01*
X36972Y-321652D01*
X36719Y-322152D01*
X36339Y-322568D01*
X35895Y-322735D01*
X35389Y-322568D01*
X34945Y-322068D01*
X34692Y-321318D01*
X34629Y-320485D01*
X34755Y-319402D01*
X34945Y-318818D01*
X35262Y-318235D01*
X35705Y-317818D01*
X36149Y-317735D01*
X36592Y-317902D01*
X36909Y-318318D01*
G01X40932Y-322735D02*
Y-317735D01*
X40172Y-318735D01*
G01Y-322735D02*
X41692D01*
G01X46792D02*
Y-317735D01*
X44449Y-321318D01*
X47615D01*
G01X-129168Y-252735D02*
Y-327735D01*
X370832D01*
Y-252735D01*
X-129168D01*
G01X65832D02*
Y-327735D01*
G01Y-302735D02*
X168832D01*
Y-277735D01*
G01X65832D02*
X168832D01*
G01X176339Y-312735D02*
Y-307735D01*
X177605D01*
X178112Y-307985D01*
X178492Y-308318D01*
X178809Y-308818D01*
X179062Y-309402D01*
X179125Y-310235D01*
X179062Y-311068D01*
X178809Y-311652D01*
X178492Y-312152D01*
X178112Y-312485D01*
X177605Y-312735D01*
X176339D01*
G01X181249D02*
X182832Y-307735D01*
X184415Y-312735D01*
G01X183845Y-310985D02*
X181819D01*
G01X187932Y-307735D02*
Y-312735D01*
G01X186475Y-307735D02*
X189389D01*
G01X194299Y-312735D02*
X191765D01*
Y-307735D01*
X194299D01*
G01X193285Y-310152D02*
X191765D01*
G01X198132Y-312902D02*
X198005Y-312818D01*
Y-312652D01*
X198132Y-312568D01*
X198259Y-312652D01*
Y-312818D01*
X198132Y-312902D01*
G01Y-310652D02*
X198005Y-310568D01*
Y-310402D01*
X198132Y-310318D01*
X198259Y-310402D01*
Y-310568D01*
X198132Y-310652D01*
G01X170832Y-252735D02*
Y-327735D01*
G01X168832Y-252735D02*
Y-327735D01*
G01X170832Y-302735D02*
X370832D01*
G01X176465Y-287735D02*
Y-282735D01*
X177985D01*
X178492Y-282985D01*
X178872Y-283568D01*
X178999Y-284235D01*
X178872Y-284902D01*
X178555Y-285402D01*
X177985Y-285652D01*
X176465D01*
G01X181692Y-287902D02*
X183972Y-282735D01*
G01X186475Y-287735D02*
Y-282735D01*
X189389Y-287735D01*
Y-282735D01*
G01X193032Y-287902D02*
X192905Y-287818D01*
Y-287652D01*
X193032Y-287568D01*
X193159Y-287652D01*
Y-287818D01*
X193032Y-287902D01*
G01Y-285652D02*
X192905Y-285568D01*
Y-285402D01*
X193032Y-285318D01*
X193159Y-285402D01*
Y-285568D01*
X193032Y-285652D01*
G01X170832Y-277735D02*
X370832D01*
G01X176465Y-262735D02*
Y-257735D01*
X177985D01*
X178492Y-257985D01*
X178872Y-258568D01*
X178999Y-259235D01*
X178872Y-259902D01*
X178555Y-260402D01*
X177985Y-260652D01*
X176465D01*
G01X181565Y-262735D02*
Y-257735D01*
X183149D01*
X183655Y-257985D01*
X183972Y-258318D01*
X184099Y-258985D01*
X183972Y-259652D01*
X183592Y-260068D01*
X183149Y-260318D01*
X181565D01*
G01X183149D02*
X184099Y-262735D01*
G01X187932D02*
X187425Y-262652D01*
X186982Y-262318D01*
X186602Y-261818D01*
X186349Y-261235D01*
X186222Y-260568D01*
Y-259902D01*
X186349Y-259235D01*
X186602Y-258652D01*
X186982Y-258152D01*
X187425Y-257818D01*
X187932Y-257735D01*
X188439Y-257818D01*
X188882Y-258152D01*
X189262Y-258652D01*
X189515Y-259235D01*
X189642Y-259902D01*
Y-260568D01*
X189515Y-261235D01*
X189262Y-261818D01*
X188882Y-262318D01*
X188439Y-262652D01*
X187932Y-262735D01*
G01X191765Y-261735D02*
X192082Y-262235D01*
X192462Y-262568D01*
X192905Y-262735D01*
X193412Y-262568D01*
X193792Y-262235D01*
X194172Y-261735D01*
X194299Y-261068D01*
Y-257735D01*
G01X199399Y-262735D02*
X196865D01*
Y-257735D01*
X199399D01*
G01X198385Y-260152D02*
X196865D01*
G01X204625Y-258152D02*
X204245Y-257902D01*
X203802Y-257735D01*
X203295D01*
X202725Y-257985D01*
X202282Y-258402D01*
X201965Y-258902D01*
X201712Y-259735D01*
X201649Y-260485D01*
X201775Y-261235D01*
X201965Y-261735D01*
X202345Y-262235D01*
X202789Y-262568D01*
X203232Y-262735D01*
X203675D01*
X204119Y-262568D01*
X204499Y-262318D01*
X204815Y-261985D01*
G01X208332Y-257735D02*
Y-262735D01*
G01X206875Y-257735D02*
X209789D01*
G01X213432Y-262902D02*
X213305Y-262818D01*
Y-262652D01*
X213432Y-262568D01*
X213559Y-262652D01*
Y-262818D01*
X213432Y-262902D01*
G01Y-260652D02*
X213305Y-260568D01*
Y-260402D01*
X213432Y-260318D01*
X213559Y-260402D01*
Y-260568D01*
X213432Y-260652D01*
G01X283832Y-302735D02*
Y-327735D01*
G01X288465Y-305235D02*
Y-310235D01*
X290999D01*
G01X294072Y-305235D02*
X295592D01*
G01X294832D02*
Y-310235D01*
G01X294072D02*
X295592D01*
G01X300439Y-307568D02*
X300692Y-307318D01*
X300882Y-306902D01*
X301009Y-306318D01*
X300882Y-305818D01*
X300629Y-305485D01*
X300185Y-305235D01*
X298475D01*
Y-310235D01*
X300565D01*
X301009Y-309902D01*
X301262Y-309402D01*
X301389Y-308818D01*
X301262Y-308235D01*
X300882Y-307735D01*
X300439Y-307568D01*
X298475D01*
G01X305032Y-310402D02*
X304905Y-310318D01*
Y-310152D01*
X305032Y-310068D01*
X305159Y-310152D01*
Y-310318D01*
X305032Y-310402D01*
G01Y-308152D02*
X304905Y-308068D01*
Y-307902D01*
X305032Y-307818D01*
X305159Y-307902D01*
Y-308068D01*
X305032Y-308152D01*
G01X328832Y-302735D02*
Y-327735D01*
G01X332732Y-305235D02*
Y-310235D01*
G01X331275Y-305235D02*
X334189D01*
G01X337832Y-310235D02*
X337452Y-310152D01*
X337072Y-309818D01*
X336819Y-309235D01*
X336692Y-308568D01*
X336819Y-307902D01*
X337072Y-307318D01*
X337452Y-306985D01*
X337832Y-306902D01*
X338212Y-306985D01*
X338592Y-307318D01*
X338845Y-307902D01*
X338909Y-308568D01*
X338845Y-309235D01*
X338592Y-309818D01*
X338212Y-310152D01*
X337832Y-310235D01*
G01X342932D02*
X342552Y-310152D01*
X342172Y-309818D01*
X341919Y-309235D01*
X341792Y-308568D01*
X341919Y-307902D01*
X342172Y-307318D01*
X342552Y-306985D01*
X342932Y-306902D01*
X343312Y-306985D01*
X343692Y-307318D01*
X343945Y-307902D01*
X344009Y-308568D01*
X343945Y-309235D01*
X343692Y-309818D01*
X343312Y-310152D01*
X342932Y-310235D01*
G01X348032D02*
Y-305235D01*
G01X353132Y-310402D02*
X353005Y-310318D01*
Y-310152D01*
X353132Y-310068D01*
X353259Y-310152D01*
Y-310318D01*
X353132Y-310402D01*
G01Y-308152D02*
X353005Y-308068D01*
Y-307902D01*
X353132Y-307818D01*
X353259Y-307902D01*
Y-308068D01*
X353132Y-308152D01*
G01X328832Y-277735D02*
Y-302735D01*
G01X331465Y-285235D02*
Y-280235D01*
X333049D01*
X333555Y-280485D01*
X333872Y-280818D01*
X333999Y-281485D01*
X333872Y-282152D01*
X333492Y-282568D01*
X333049Y-282818D01*
X331465D01*
G01X333049D02*
X333999Y-285235D01*
G01X339099D02*
X336565D01*
Y-280235D01*
X339099D01*
G01X338085Y-282652D02*
X336565D01*
G01X341349Y-280235D02*
X342932Y-285235D01*
X344515Y-280235D01*
G01X348032Y-285402D02*
X347905Y-285318D01*
Y-285152D01*
X348032Y-285068D01*
X348159Y-285152D01*
Y-285318D01*
X348032Y-285402D01*
G01Y-283152D02*
X347905Y-283068D01*
Y-282902D01*
X348032Y-282818D01*
X348159Y-282902D01*
Y-283068D01*
X348032Y-283152D01*
G01X351592Y-329435D02*
X351672Y-329360D01*
X351732Y-329235D01*
X351772Y-329060D01*
X351732Y-328910D01*
X351652Y-328810D01*
X351512Y-328735D01*
X350972D01*
Y-330235D01*
X351632D01*
X351772Y-330135D01*
X351852Y-329985D01*
X351892Y-329810D01*
X351852Y-329635D01*
X351732Y-329485D01*
X351592Y-329435D01*
X350972D01*
G01X352992Y-330235D02*
Y-329235D01*
G01Y-329410D02*
X352912Y-329310D01*
X352792Y-329260D01*
X352652Y-329235D01*
X352512Y-329285D01*
X352392Y-329385D01*
X352312Y-329535D01*
X352272Y-329735D01*
X352312Y-329935D01*
X352392Y-330085D01*
X352512Y-330185D01*
X352652Y-330235D01*
X352792Y-330210D01*
X352912Y-330135D01*
X352992Y-330035D01*
G01X353532Y-330060D02*
X353632Y-330160D01*
X353772Y-330235D01*
X353892D01*
X354012Y-330185D01*
X354092Y-330110D01*
X354132Y-330010D01*
X354112Y-329860D01*
X354032Y-329785D01*
X353672Y-329635D01*
X353592Y-329460D01*
X353632Y-329335D01*
X353712Y-329260D01*
X353832Y-329235D01*
X353952Y-329260D01*
X354072Y-329335D01*
G01X354732Y-329560D02*
X355372D01*
X355312Y-329385D01*
X355212Y-329285D01*
X355072Y-329235D01*
X354932Y-329260D01*
X354812Y-329335D01*
X354732Y-329510D01*
X354692Y-329660D01*
Y-329810D01*
X354732Y-329960D01*
X354832Y-330110D01*
X354952Y-330210D01*
X355092Y-330235D01*
X355232Y-330185D01*
X355372Y-330035D01*
G01X355872Y-330235D02*
Y-328735D01*
G01Y-329485D02*
X355972Y-329335D01*
X356092Y-329260D01*
X356212Y-329235D01*
X356392Y-329285D01*
X356512Y-329385D01*
X356592Y-329560D01*
Y-329760D01*
X356552Y-329960D01*
X356472Y-330110D01*
X356332Y-330210D01*
X356212Y-330235D01*
X356092Y-330210D01*
X355972Y-330135D01*
X355872Y-330010D01*
G01X357432Y-330235D02*
X357312Y-330210D01*
X357192Y-330110D01*
X357112Y-329935D01*
X357072Y-329735D01*
X357112Y-329535D01*
X357192Y-329360D01*
X357312Y-329260D01*
X357432Y-329235D01*
X357552Y-329260D01*
X357672Y-329360D01*
X357752Y-329535D01*
X357772Y-329735D01*
X357752Y-329935D01*
X357672Y-330110D01*
X357552Y-330210D01*
X357432Y-330235D01*
G01X358992D02*
Y-329235D01*
G01Y-329410D02*
X358912Y-329310D01*
X358792Y-329260D01*
X358652Y-329235D01*
X358512Y-329285D01*
X358392Y-329385D01*
X358312Y-329535D01*
X358272Y-329735D01*
X358312Y-329935D01*
X358392Y-330085D01*
X358512Y-330185D01*
X358652Y-330235D01*
X358792Y-330210D01*
X358912Y-330135D01*
X358992Y-330035D01*
G01X359552Y-330235D02*
Y-329235D01*
G01Y-329435D02*
X359652Y-329335D01*
X359752Y-329260D01*
X359892Y-329235D01*
X359992Y-329260D01*
X360112Y-329335D01*
G01X361392Y-328735D02*
Y-330235D01*
G01Y-330010D02*
X361312Y-330135D01*
X361192Y-330210D01*
X361052Y-330235D01*
X360892Y-330185D01*
X360772Y-330060D01*
X360692Y-329910D01*
X360672Y-329735D01*
X360692Y-329560D01*
X360772Y-329410D01*
X360892Y-329285D01*
X361052Y-329235D01*
X361192Y-329260D01*
X361292Y-329310D01*
X361392Y-329410D01*
G01X363032Y-330235D02*
Y-328735D01*
X363532D01*
X363692Y-328810D01*
X363792Y-328910D01*
X363832Y-329110D01*
X363792Y-329310D01*
X363672Y-329435D01*
X363532Y-329510D01*
X363032D01*
G01X363532D02*
X363832Y-330235D01*
G01X364332Y-329560D02*
X364972D01*
X364912Y-329385D01*
X364812Y-329285D01*
X364672Y-329235D01*
X364532Y-329260D01*
X364412Y-329335D01*
X364332Y-329510D01*
X364292Y-329660D01*
Y-329810D01*
X364332Y-329960D01*
X364432Y-330110D01*
X364552Y-330210D01*
X364692Y-330235D01*
X364832Y-330185D01*
X364972Y-330035D01*
G01X365472Y-329235D02*
X365832Y-330235D01*
X366192Y-329235D01*
G01X367032Y-330285D02*
X366992Y-330260D01*
Y-330210D01*
X367032Y-330185D01*
X367072Y-330210D01*
Y-330260D01*
X367032Y-330285D01*
G01X368192Y-330235D02*
X368232Y-329910D01*
X368292Y-329635D01*
X368372Y-329385D01*
X368472Y-329110D01*
X368632Y-328735D01*
X367832D01*
G01X369592Y-329435D02*
X369672Y-329360D01*
X369732Y-329235D01*
X369772Y-329060D01*
X369732Y-328910D01*
X369652Y-328810D01*
X369512Y-328735D01*
X368972D01*
Y-330235D01*
X369632D01*
X369772Y-330135D01*
X369852Y-329985D01*
X369892Y-329810D01*
X369852Y-329635D01*
X369732Y-329485D01*
X369592Y-329435D01*
X368972D01*
G01X-247901Y-428634D02*
Y1008173D01*
X2091018D01*
Y-428634D01*
X-247901D01*
G01X-115095Y-307460D02*
X-115565Y-307145D01*
X-116113Y-306935D01*
X-116740D01*
X-117445Y-307250D01*
X-117993Y-307775D01*
X-118385Y-308405D01*
X-118698Y-309455D01*
X-118776Y-310400D01*
X-118620Y-311345D01*
X-118385Y-311975D01*
X-117915Y-312605D01*
X-117366Y-313025D01*
X-116818Y-313235D01*
X-116270D01*
X-115721Y-313025D01*
X-115251Y-312710D01*
X-114860Y-312290D01*
G01X-111458Y-306935D02*
X-109578D01*
G01X-110518D02*
Y-313235D01*
G01X-111458D02*
X-109578D01*
G01X-104218Y-306935D02*
Y-313235D01*
G01X-106020Y-306935D02*
X-102416D01*
G01X-97918Y-313235D02*
Y-310400D01*
X-99485Y-306935D01*
G01X-96351D02*
X-97918Y-310400D01*
G01X-87041Y-311975D02*
X-86571Y-312710D01*
X-85945Y-313130D01*
X-85240Y-313235D01*
X-84613Y-313130D01*
X-83986Y-312605D01*
X-83595Y-311975D01*
X-83516Y-311345D01*
X-83673Y-310610D01*
X-84221Y-310085D01*
X-84770Y-309875D01*
X-85475D01*
G01X-84770D02*
X-84300Y-309560D01*
X-83908Y-309035D01*
X-83751Y-308405D01*
X-83908Y-307775D01*
X-84300Y-307250D01*
X-85005Y-306935D01*
X-85710Y-307040D01*
X-86415Y-307460D01*
G01X-80741Y-311975D02*
X-80271Y-312710D01*
X-79645Y-313130D01*
X-78940Y-313235D01*
X-78313Y-313130D01*
X-77686Y-312605D01*
X-77295Y-311975D01*
X-77216Y-311345D01*
X-77373Y-310610D01*
X-77921Y-310085D01*
X-78470Y-309875D01*
X-79175D01*
G01X-78470D02*
X-78000Y-309560D01*
X-77608Y-309035D01*
X-77451Y-308405D01*
X-77608Y-307775D01*
X-78000Y-307250D01*
X-78705Y-306935D01*
X-79410Y-307040D01*
X-80115Y-307460D01*
G01X-74441Y-311975D02*
X-73971Y-312710D01*
X-73345Y-313130D01*
X-72640Y-313235D01*
X-72013Y-313130D01*
X-71386Y-312605D01*
X-70995Y-311975D01*
X-70916Y-311345D01*
X-71073Y-310610D01*
X-71621Y-310085D01*
X-72170Y-309875D01*
X-72875D01*
G01X-72170D02*
X-71700Y-309560D01*
X-71308Y-309035D01*
X-71151Y-308405D01*
X-71308Y-307775D01*
X-71700Y-307250D01*
X-72405Y-306935D01*
X-73110Y-307040D01*
X-73815Y-307460D01*
G01X-66575Y-313235D02*
X-66418Y-311870D01*
X-66183Y-310715D01*
X-65870Y-309665D01*
X-65478Y-308510D01*
X-64851Y-306935D01*
X-67985D01*
G01X-60275Y-313235D02*
X-60118Y-311870D01*
X-59883Y-310715D01*
X-59570Y-309665D01*
X-59178Y-308510D01*
X-58551Y-306935D01*
X-61685D01*
G01X-53975Y-314390D02*
X-53661Y-313025D01*
G01X-47518Y-306935D02*
Y-313235D01*
G01X-49320Y-306935D02*
X-45716D01*
G01X-43176Y-313235D02*
X-41218Y-306935D01*
X-39260Y-313235D01*
G01X-39965Y-311030D02*
X-42471D01*
G01X-35858Y-306935D02*
X-33978D01*
G01X-34918D02*
Y-313235D01*
G01X-35858D02*
X-33978D01*
G01X-30968Y-306935D02*
X-29871Y-313235D01*
X-28618Y-306935D01*
X-27365Y-313235D01*
X-26268Y-306935D01*
G01X-24276Y-313235D02*
X-22318Y-306935D01*
X-20360Y-313235D01*
G01X-21065Y-311030D02*
X-23571D01*
G01X-17820Y-313235D02*
Y-306935D01*
X-14216Y-313235D01*
Y-306935D01*
G01X-3810Y-315335D02*
X-4593Y-314285D01*
X-4985Y-313235D01*
Y-309035D01*
X-4593Y-307985D01*
X-3810Y-306935D01*
G01X7615Y-313235D02*
Y-306935D01*
X9574D01*
X10200Y-307250D01*
X10592Y-307670D01*
X10749Y-308510D01*
X10592Y-309350D01*
X10122Y-309875D01*
X9574Y-310190D01*
X7615D01*
G01X9574D02*
X10749Y-313235D01*
G01X15482Y-313445D02*
X15325Y-313340D01*
Y-313130D01*
X15482Y-313025D01*
X15639Y-313130D01*
Y-313340D01*
X15482Y-313445D01*
G01X21782Y-313235D02*
X21155Y-313130D01*
X20607Y-312710D01*
X20137Y-312080D01*
X19824Y-311345D01*
X19667Y-310505D01*
Y-309665D01*
X19824Y-308825D01*
X20137Y-308090D01*
X20607Y-307460D01*
X21155Y-307040D01*
X21782Y-306935D01*
X22409Y-307040D01*
X22957Y-307460D01*
X23427Y-308090D01*
X23740Y-308825D01*
X23897Y-309665D01*
Y-310505D01*
X23740Y-311345D01*
X23427Y-312080D01*
X22957Y-312710D01*
X22409Y-313130D01*
X21782Y-313235D01*
G01X28082Y-313445D02*
X27925Y-313340D01*
Y-313130D01*
X28082Y-313025D01*
X28239Y-313130D01*
Y-313340D01*
X28082Y-313445D01*
G01X36105Y-307460D02*
X35635Y-307145D01*
X35087Y-306935D01*
X34460D01*
X33755Y-307250D01*
X33207Y-307775D01*
X32815Y-308405D01*
X32502Y-309455D01*
X32424Y-310400D01*
X32580Y-311345D01*
X32815Y-311975D01*
X33285Y-312605D01*
X33834Y-313025D01*
X34382Y-313235D01*
X34930D01*
X35479Y-313025D01*
X35949Y-312710D01*
X36340Y-312290D01*
G01X40682Y-313445D02*
X40525Y-313340D01*
Y-313130D01*
X40682Y-313025D01*
X40839Y-313130D01*
Y-313340D01*
X40682Y-313445D01*
G01X47374Y-315335D02*
X48157Y-314285D01*
X48549Y-313235D01*
Y-309035D01*
X48157Y-307985D01*
X47374Y-306935D01*
G01X-118620Y-293235D02*
Y-286935D01*
X-115016Y-293235D01*
Y-286935D01*
G01X-110518Y-293235D02*
X-111145Y-293130D01*
X-111693Y-292710D01*
X-112163Y-292080D01*
X-112476Y-291345D01*
X-112633Y-290505D01*
Y-289665D01*
X-112476Y-288825D01*
X-112163Y-288090D01*
X-111693Y-287460D01*
X-111145Y-287040D01*
X-110518Y-286935D01*
X-109891Y-287040D01*
X-109343Y-287460D01*
X-108873Y-288090D01*
X-108560Y-288825D01*
X-108403Y-289665D01*
Y-290505D01*
X-108560Y-291345D01*
X-108873Y-292080D01*
X-109343Y-292710D01*
X-109891Y-293130D01*
X-110518Y-293235D01*
G01X-104218Y-293445D02*
X-104375Y-293340D01*
Y-293130D01*
X-104218Y-293025D01*
X-104061Y-293130D01*
Y-293340D01*
X-104218Y-293445D01*
G01X-99406Y-287985D02*
X-98936Y-287355D01*
X-98388Y-287040D01*
X-97761Y-286935D01*
X-96978Y-287145D01*
X-96430Y-287670D01*
X-96273Y-288300D01*
X-96351Y-288930D01*
X-96665Y-289455D01*
X-98231Y-290505D01*
X-98936Y-291240D01*
X-99406Y-292290D01*
X-99563Y-293235D01*
X-96273D01*
G01X-91618D02*
Y-286935D01*
X-92558Y-288195D01*
G01Y-293235D02*
X-90678D01*
G01X-85318D02*
Y-286935D01*
X-86258Y-288195D01*
G01Y-293235D02*
X-84378D01*
G01X-79175Y-294390D02*
X-78861Y-293025D01*
G01X-75068Y-286935D02*
X-73971Y-293235D01*
X-72718Y-286935D01*
X-71465Y-293235D01*
X-70368Y-286935D01*
G01X-64851Y-293235D02*
X-67985D01*
Y-286935D01*
X-64851D01*
G01X-66105Y-289980D02*
X-67985D01*
G01X-61920Y-293235D02*
Y-286935D01*
X-58316Y-293235D01*
Y-286935D01*
G01X-55463Y-293235D02*
Y-286935D01*
G01X-52173D02*
Y-293235D01*
G01Y-290085D02*
X-55463D01*
G01X-49241Y-286935D02*
Y-291450D01*
X-48928Y-292395D01*
X-48301Y-293025D01*
X-47518Y-293235D01*
X-46735Y-293025D01*
X-46108Y-292395D01*
X-45795Y-291450D01*
Y-286935D01*
G01X-43176Y-293235D02*
X-41218Y-286935D01*
X-39260Y-293235D01*
G01X-39965Y-291030D02*
X-42471D01*
G01X-30106Y-287985D02*
X-29636Y-287355D01*
X-29088Y-287040D01*
X-28461Y-286935D01*
X-27678Y-287145D01*
X-27130Y-287670D01*
X-26973Y-288300D01*
X-27051Y-288930D01*
X-27365Y-289455D01*
X-28931Y-290505D01*
X-29636Y-291240D01*
X-30106Y-292290D01*
X-30263Y-293235D01*
X-26973D01*
G01X-24120D02*
Y-286935D01*
X-20516Y-293235D01*
Y-286935D01*
G01X-17741Y-293235D02*
Y-286935D01*
X-16175D01*
X-15548Y-287250D01*
X-15078Y-287670D01*
X-14686Y-288300D01*
X-14373Y-289035D01*
X-14295Y-290085D01*
X-14373Y-291135D01*
X-14686Y-291870D01*
X-15078Y-292500D01*
X-15548Y-292920D01*
X-16175Y-293235D01*
X-17741D01*
G01X-4985D02*
Y-286935D01*
X-3026D01*
X-2400Y-287250D01*
X-2008Y-287670D01*
X-1851Y-288510D01*
X-2008Y-289350D01*
X-2478Y-289875D01*
X-3026Y-290190D01*
X-4985D01*
G01X-3026D02*
X-1851Y-293235D01*
G01X1159D02*
Y-286935D01*
X2725D01*
X3352Y-287250D01*
X3822Y-287670D01*
X4214Y-288300D01*
X4527Y-289035D01*
X4605Y-290085D01*
X4527Y-291135D01*
X4214Y-291870D01*
X3822Y-292500D01*
X3352Y-292920D01*
X2725Y-293235D01*
X1159D01*
G01X9182Y-293445D02*
X9025Y-293340D01*
Y-293130D01*
X9182Y-293025D01*
X9339Y-293130D01*
Y-293340D01*
X9182Y-293445D01*
G01X-116348Y-300085D02*
X-114781D01*
Y-301975D01*
X-115251Y-302605D01*
X-115800Y-303025D01*
X-116583Y-303235D01*
X-117366Y-303025D01*
X-117915Y-302605D01*
X-118385Y-301975D01*
X-118698Y-301240D01*
X-118855Y-300400D01*
Y-299665D01*
X-118698Y-299035D01*
X-118385Y-298300D01*
X-117915Y-297670D01*
X-117445Y-297250D01*
X-116818Y-296935D01*
X-116270D01*
X-115643Y-297145D01*
X-115173Y-297565D01*
G01X-112241Y-296935D02*
Y-301450D01*
X-111928Y-302395D01*
X-111301Y-303025D01*
X-110518Y-303235D01*
X-109735Y-303025D01*
X-109108Y-302395D01*
X-108795Y-301450D01*
Y-296935D01*
G01X-105158D02*
X-103278D01*
G01X-104218D02*
Y-303235D01*
G01X-105158D02*
X-103278D01*
G01X-99563Y-302395D02*
X-98936Y-302920D01*
X-98231Y-303235D01*
X-97605D01*
X-96978Y-302920D01*
X-96508Y-302395D01*
X-96273Y-301660D01*
X-96430Y-300925D01*
X-96821Y-300295D01*
X-97526Y-299875D01*
X-98466Y-299665D01*
X-99015Y-299245D01*
X-99250Y-298510D01*
X-99093Y-297775D01*
X-98701Y-297250D01*
X-98153Y-296935D01*
X-97605D01*
X-97056Y-297145D01*
X-96586Y-297670D01*
G01X-93263Y-303235D02*
Y-296935D01*
G01X-89973D02*
Y-303235D01*
G01Y-300085D02*
X-93263D01*
G01X-87276Y-303235D02*
X-85318Y-296935D01*
X-83360Y-303235D01*
G01X-84065Y-301030D02*
X-86571D01*
G01X-80820Y-303235D02*
Y-296935D01*
X-77216Y-303235D01*
Y-296935D01*
G01X-68141Y-303235D02*
Y-296935D01*
X-66575D01*
X-65948Y-297250D01*
X-65478Y-297670D01*
X-65086Y-298300D01*
X-64773Y-299035D01*
X-64695Y-300085D01*
X-64773Y-301135D01*
X-65086Y-301870D01*
X-65478Y-302500D01*
X-65948Y-302920D01*
X-66575Y-303235D01*
X-68141D01*
G01X-61058Y-296935D02*
X-59178D01*
G01X-60118D02*
Y-303235D01*
G01X-61058D02*
X-59178D01*
G01X-55463Y-302395D02*
X-54836Y-302920D01*
X-54131Y-303235D01*
X-53505D01*
X-52878Y-302920D01*
X-52408Y-302395D01*
X-52173Y-301660D01*
X-52330Y-300925D01*
X-52721Y-300295D01*
X-53426Y-299875D01*
X-54366Y-299665D01*
X-54915Y-299245D01*
X-55150Y-298510D01*
X-54993Y-297775D01*
X-54601Y-297250D01*
X-54053Y-296935D01*
X-53505D01*
X-52956Y-297145D01*
X-52486Y-297670D01*
G01X-47518Y-296935D02*
Y-303235D01*
G01X-49320Y-296935D02*
X-45716D01*
G01X-41218Y-303445D02*
X-41375Y-303340D01*
Y-303130D01*
X-41218Y-303025D01*
X-41061Y-303130D01*
Y-303340D01*
X-41218Y-303445D01*
G01X-35075Y-304390D02*
X-34761Y-303025D01*
G01X-28618Y-296935D02*
Y-303235D01*
G01X-30420Y-296935D02*
X-26816D01*
G01X-24276Y-303235D02*
X-22318Y-296935D01*
X-20360Y-303235D01*
G01X-21065Y-301030D02*
X-23571D01*
G01X-16018Y-303235D02*
X-16645Y-303130D01*
X-17193Y-302710D01*
X-17663Y-302080D01*
X-17976Y-301345D01*
X-18133Y-300505D01*
Y-299665D01*
X-17976Y-298825D01*
X-17663Y-298090D01*
X-17193Y-297460D01*
X-16645Y-297040D01*
X-16018Y-296935D01*
X-15391Y-297040D01*
X-14843Y-297460D01*
X-14373Y-298090D01*
X-14060Y-298825D01*
X-13903Y-299665D01*
Y-300505D01*
X-14060Y-301345D01*
X-14373Y-302080D01*
X-14843Y-302710D01*
X-15391Y-303130D01*
X-16018Y-303235D01*
G01X-9718D02*
Y-300400D01*
X-11285Y-296935D01*
G01X-8151D02*
X-9718Y-300400D01*
G01X-5141Y-296935D02*
Y-301450D01*
X-4828Y-302395D01*
X-4201Y-303025D01*
X-3418Y-303235D01*
X-2635Y-303025D01*
X-2008Y-302395D01*
X-1695Y-301450D01*
Y-296935D01*
G01X924Y-303235D02*
X2882Y-296935D01*
X4840Y-303235D01*
G01X4135Y-301030D02*
X1629D01*
G01X7380Y-303235D02*
Y-296935D01*
X10984Y-303235D01*
Y-296935D01*
G01X-94518Y-282535D02*
X-97038Y-282118D01*
X-99243Y-280452D01*
X-101133Y-277952D01*
X-102393Y-275035D01*
X-103023Y-271702D01*
Y-268368D01*
X-102393Y-265035D01*
X-101133Y-262118D01*
X-99243Y-259619D01*
X-97038Y-257952D01*
X-94518Y-257535D01*
X-91998Y-257952D01*
X-89793Y-259619D01*
X-87903Y-262118D01*
X-86643Y-265035D01*
X-86013Y-268368D01*
Y-271702D01*
X-86643Y-275035D01*
X-87903Y-277952D01*
X-89793Y-280452D01*
X-91998Y-282118D01*
X-94518Y-282535D01*
G01X-91998Y-275868D02*
X-88218Y-282535D01*
G01X-74673Y-265869D02*
Y-277535D01*
X-73413Y-280452D01*
X-71523Y-282118D01*
X-69318Y-282535D01*
X-67113Y-282118D01*
X-65223Y-280452D01*
X-63963Y-277535D01*
G01Y-282535D02*
Y-265869D01*
G01X-38448Y-282535D02*
Y-265869D01*
G01Y-268785D02*
X-39708Y-267119D01*
X-41598Y-266285D01*
X-43803Y-265869D01*
X-46008Y-266702D01*
X-47898Y-268368D01*
X-49158Y-270869D01*
X-49788Y-274202D01*
X-49158Y-277535D01*
X-47898Y-280036D01*
X-46008Y-281702D01*
X-43803Y-282535D01*
X-41598Y-282118D01*
X-39708Y-280869D01*
X-38448Y-279202D01*
G01X-24273Y-282535D02*
Y-265869D01*
G01Y-270035D02*
X-23013Y-267952D01*
X-21123Y-266285D01*
X-18603Y-265869D01*
X-16398Y-266285D01*
X-14508Y-267952D01*
X-13563Y-270869D01*
Y-282535D01*
G01X6282Y-257535D02*
Y-282535D01*
G01X1872Y-265869D02*
X10692D01*
G01X37152Y-282535D02*
Y-265869D01*
G01Y-268785D02*
X35892Y-267119D01*
X34002Y-266285D01*
X31797Y-265869D01*
X29592Y-266702D01*
X27702Y-268368D01*
X26442Y-270869D01*
X25812Y-274202D01*
X26442Y-277535D01*
X27702Y-280036D01*
X29592Y-281702D01*
X31797Y-282535D01*
X34002Y-282118D01*
X35892Y-280869D01*
X37152Y-279202D01*
G01X76832Y-262235D02*
Y-270235D01*
X80832D01*
G01X88632D02*
Y-264902D01*
G01Y-265835D02*
X88232Y-265302D01*
X87632Y-265035D01*
X86932Y-264902D01*
X86232Y-265168D01*
X85632Y-265702D01*
X85232Y-266502D01*
X85032Y-267568D01*
X85232Y-268635D01*
X85632Y-269435D01*
X86232Y-269968D01*
X86932Y-270235D01*
X87632Y-270102D01*
X88232Y-269702D01*
X88632Y-269169D01*
G01X92732Y-272635D02*
X93332Y-272902D01*
X94132Y-272635D01*
X94632Y-272102D01*
X95032Y-271435D01*
X95632Y-269302D01*
X96932Y-264902D01*
G01X93732D02*
X95632Y-269302D01*
G01X101332Y-266635D02*
X104532D01*
X104232Y-265702D01*
X103732Y-265168D01*
X103032Y-264902D01*
X102332Y-265035D01*
X101732Y-265435D01*
X101332Y-266368D01*
X101132Y-267169D01*
Y-267968D01*
X101332Y-268768D01*
X101832Y-269568D01*
X102432Y-270102D01*
X103132Y-270235D01*
X103832Y-269968D01*
X104532Y-269169D01*
G01X109432Y-270235D02*
Y-264902D01*
G01Y-265968D02*
X109932Y-265435D01*
X110432Y-265035D01*
X111132Y-264902D01*
X111632Y-265035D01*
X112232Y-265435D01*
G01X95532Y-320235D02*
Y-312235D01*
X100132Y-320235D01*
Y-312235D01*
G01X105832Y-314902D02*
Y-320235D01*
G01Y-312768D02*
X105632Y-312635D01*
Y-312368D01*
X105832Y-312235D01*
X106032Y-312368D01*
Y-312635D01*
X105832Y-312768D01*
G01X112132Y-320235D02*
Y-314902D01*
G01Y-316235D02*
X112532Y-315568D01*
X113132Y-315035D01*
X113932Y-314902D01*
X114632Y-315035D01*
X115232Y-315568D01*
X115532Y-316502D01*
Y-320235D01*
G01X123632D02*
Y-314902D01*
G01Y-315835D02*
X123232Y-315302D01*
X122632Y-315035D01*
X121932Y-314902D01*
X121232Y-315168D01*
X120632Y-315702D01*
X120232Y-316502D01*
X120032Y-317568D01*
X120232Y-318635D01*
X120632Y-319435D01*
X121232Y-319968D01*
X121932Y-320235D01*
X122632Y-320102D01*
X123232Y-319702D01*
X123632Y-319169D01*
G01X90232Y-295235D02*
Y-287235D01*
X92832Y-293902D01*
X95432Y-287235D01*
Y-295235D01*
G01X98332D02*
X100832Y-287235D01*
X103332Y-295235D01*
G01X102432Y-292435D02*
X99232D01*
G01X106732Y-294169D02*
X107532Y-294835D01*
X108432Y-295235D01*
X109232D01*
X110032Y-294835D01*
X110632Y-294169D01*
X110932Y-293235D01*
X110732Y-292302D01*
X110232Y-291502D01*
X109332Y-290968D01*
X108132Y-290702D01*
X107432Y-290168D01*
X107132Y-289235D01*
X107332Y-288302D01*
X107832Y-287635D01*
X108532Y-287235D01*
X109232D01*
X109932Y-287502D01*
X110532Y-288168D01*
G01X114632Y-295235D02*
Y-287235D01*
G01X118432D02*
X114632Y-292169D01*
G01X119032Y-295235D02*
X116332Y-289902D01*
G01X123532Y-292568D02*
X126132D01*
G01X133632Y-290968D02*
X134032Y-290568D01*
X134332Y-289902D01*
X134532Y-288968D01*
X134332Y-288168D01*
X133932Y-287635D01*
X133232Y-287235D01*
X130532D01*
Y-295235D01*
X133832D01*
X134532Y-294702D01*
X134932Y-293902D01*
X135132Y-292968D01*
X134932Y-292035D01*
X134332Y-291235D01*
X133632Y-290968D01*
X130532D01*
G01X140832Y-295235D02*
X140032Y-295102D01*
X139332Y-294568D01*
X138732Y-293768D01*
X138332Y-292835D01*
X138132Y-291768D01*
Y-290702D01*
X138332Y-289635D01*
X138732Y-288702D01*
X139332Y-287902D01*
X140032Y-287368D01*
X140832Y-287235D01*
X141632Y-287368D01*
X142332Y-287902D01*
X142932Y-288702D01*
X143332Y-289635D01*
X143532Y-290702D01*
Y-291768D01*
X143332Y-292835D01*
X142932Y-293768D01*
X142332Y-294568D01*
X141632Y-295102D01*
X140832Y-295235D01*
G01X148832Y-287235D02*
Y-295235D01*
G01X146532Y-287235D02*
X151132D01*
G01X203432Y-313568D02*
X204032Y-312768D01*
X204732Y-312368D01*
X205532Y-312235D01*
X206532Y-312502D01*
X207232Y-313168D01*
X207432Y-313968D01*
X207332Y-314769D01*
X206932Y-315435D01*
X204932Y-316768D01*
X204032Y-317702D01*
X203432Y-319035D01*
X203232Y-320235D01*
X207432D01*
G01X213332Y-312235D02*
X212532Y-312502D01*
X211932Y-313168D01*
X211532Y-313968D01*
X211232Y-315035D01*
X211132Y-316235D01*
X211232Y-317435D01*
X211532Y-318502D01*
X211932Y-319302D01*
X212532Y-319968D01*
X213332Y-320235D01*
X214132Y-319968D01*
X214732Y-319302D01*
X215132Y-318502D01*
X215432Y-317435D01*
X215532Y-316235D01*
X215432Y-315035D01*
X215132Y-313968D01*
X214732Y-313168D01*
X214132Y-312502D01*
X213332Y-312235D01*
G01X219432Y-313568D02*
X220032Y-312768D01*
X220732Y-312368D01*
X221532Y-312235D01*
X222532Y-312502D01*
X223232Y-313168D01*
X223432Y-313968D01*
X223332Y-314769D01*
X222932Y-315435D01*
X220932Y-316768D01*
X220032Y-317702D01*
X219432Y-319035D01*
X219232Y-320235D01*
X223432D01*
G01X227432Y-313568D02*
X228032Y-312768D01*
X228732Y-312368D01*
X229532Y-312235D01*
X230532Y-312502D01*
X231232Y-313168D01*
X231432Y-313968D01*
X231332Y-314769D01*
X230932Y-315435D01*
X228932Y-316768D01*
X228032Y-317702D01*
X227432Y-319035D01*
X227232Y-320235D01*
X231432D01*
G01X235532Y-320502D02*
X239132Y-312235D01*
G01X245332Y-320235D02*
Y-312235D01*
X244132Y-313835D01*
G01Y-320235D02*
X246532D01*
G01X251432Y-313568D02*
X252032Y-312768D01*
X252732Y-312368D01*
X253532Y-312235D01*
X254532Y-312502D01*
X255232Y-313168D01*
X255432Y-313968D01*
X255332Y-314769D01*
X254932Y-315435D01*
X252932Y-316768D01*
X252032Y-317702D01*
X251432Y-319035D01*
X251232Y-320235D01*
X255432D01*
G01X259532Y-320502D02*
X263132Y-312235D01*
G01X269332D02*
X268532Y-312502D01*
X267932Y-313168D01*
X267532Y-313968D01*
X267232Y-315035D01*
X267132Y-316235D01*
X267232Y-317435D01*
X267532Y-318502D01*
X267932Y-319302D01*
X268532Y-319968D01*
X269332Y-320235D01*
X270132Y-319968D01*
X270732Y-319302D01*
X271132Y-318502D01*
X271432Y-317435D01*
X271532Y-316235D01*
X271432Y-315035D01*
X271132Y-313968D01*
X270732Y-313168D01*
X270132Y-312502D01*
X269332Y-312235D01*
G01X275632Y-319302D02*
X276332Y-319968D01*
X277132Y-320235D01*
X277932Y-319968D01*
X278632Y-319169D01*
X279132Y-317968D01*
X279332Y-316768D01*
Y-315302D01*
X279132Y-314102D01*
X278632Y-313035D01*
X278032Y-312502D01*
X277332Y-312235D01*
X276532Y-312502D01*
X275932Y-313035D01*
X275532Y-313835D01*
X275332Y-314902D01*
X275532Y-315835D01*
X276032Y-316768D01*
X276632Y-317302D01*
X277332Y-317435D01*
X278132Y-317169D01*
X278732Y-316502D01*
X279332Y-315302D01*
G01X205632Y-295235D02*
Y-287235D01*
X207632D01*
X208432Y-287635D01*
X209032Y-288168D01*
X209532Y-288968D01*
X209932Y-289902D01*
X210032Y-291235D01*
X209932Y-292568D01*
X209532Y-293502D01*
X209032Y-294302D01*
X208432Y-294835D01*
X207632Y-295235D01*
X205632D01*
G01X213332D02*
X215832Y-287235D01*
X218332Y-295235D01*
G01X217432Y-292435D02*
X214232D01*
G01X223832Y-287235D02*
X223032Y-287502D01*
X222432Y-288168D01*
X222032Y-288968D01*
X221732Y-290035D01*
X221632Y-291235D01*
X221732Y-292435D01*
X222032Y-293502D01*
X222432Y-294302D01*
X223032Y-294968D01*
X223832Y-295235D01*
X224632Y-294968D01*
X225232Y-294302D01*
X225632Y-293502D01*
X225932Y-292435D01*
X226032Y-291235D01*
X225932Y-290035D01*
X225632Y-288968D01*
X225232Y-288168D01*
X224632Y-287502D01*
X223832Y-287235D01*
G01X229932Y-295235D02*
Y-287235D01*
X233732D01*
G01X232332Y-291102D02*
X229932D01*
G01X239832Y-287235D02*
X239032Y-287502D01*
X238432Y-288168D01*
X238032Y-288968D01*
X237732Y-290035D01*
X237632Y-291235D01*
X237732Y-292435D01*
X238032Y-293502D01*
X238432Y-294302D01*
X239032Y-294968D01*
X239832Y-295235D01*
X240632Y-294968D01*
X241232Y-294302D01*
X241632Y-293502D01*
X241932Y-292435D01*
X242032Y-291235D01*
X241932Y-290035D01*
X241632Y-288968D01*
X241232Y-288168D01*
X240632Y-287502D01*
X239832Y-287235D01*
G01X247832D02*
Y-295235D01*
G01X245532Y-287235D02*
X250132D01*
G01X255832Y-295235D02*
Y-291635D01*
X253832Y-287235D01*
G01X257832D02*
X255832Y-291635D01*
G01X264632Y-290968D02*
X265032Y-290568D01*
X265332Y-289902D01*
X265532Y-288968D01*
X265332Y-288168D01*
X264932Y-287635D01*
X264232Y-287235D01*
X261532D01*
Y-295235D01*
X264832D01*
X265532Y-294702D01*
X265932Y-293902D01*
X266132Y-292968D01*
X265932Y-292035D01*
X265332Y-291235D01*
X264632Y-290968D01*
X261532D01*
G01X273032Y-295235D02*
Y-287235D01*
X269332Y-292968D01*
X274332D01*
G01X277632Y-295235D02*
Y-287235D01*
X279632D01*
X280432Y-287635D01*
X281032Y-288168D01*
X281532Y-288968D01*
X281932Y-289902D01*
X282032Y-291235D01*
X281932Y-292568D01*
X281532Y-293502D01*
X281032Y-294302D01*
X280432Y-294835D01*
X279632Y-295235D01*
X277632D01*
G01X287832Y-287235D02*
X287032Y-287502D01*
X286432Y-288168D01*
X286032Y-288968D01*
X285732Y-290035D01*
X285632Y-291235D01*
X285732Y-292435D01*
X286032Y-293502D01*
X286432Y-294302D01*
X287032Y-294968D01*
X287832Y-295235D01*
X288632Y-294968D01*
X289232Y-294302D01*
X289632Y-293502D01*
X289932Y-292435D01*
X290032Y-291235D01*
X289932Y-290035D01*
X289632Y-288968D01*
X289232Y-288168D01*
X288632Y-287502D01*
X287832Y-287235D01*
G01X233432Y-270235D02*
Y-262235D01*
X237232D01*
G01X235832Y-266102D02*
X233432D01*
G01X243332Y-262235D02*
X242532Y-262502D01*
X241932Y-263168D01*
X241532Y-263968D01*
X241232Y-265035D01*
X241132Y-266235D01*
X241232Y-267435D01*
X241532Y-268502D01*
X241932Y-269302D01*
X242532Y-269968D01*
X243332Y-270235D01*
X244132Y-269968D01*
X244732Y-269302D01*
X245132Y-268502D01*
X245432Y-267435D01*
X245532Y-266235D01*
X245432Y-265035D01*
X245132Y-263968D01*
X244732Y-263168D01*
X244132Y-262502D01*
X243332Y-262235D01*
G01X251332D02*
Y-270235D01*
G01X249032Y-262235D02*
X253632D01*
G01X256332Y-272902D02*
X262332D01*
G01X265332Y-270235D02*
Y-262235D01*
X267732D01*
X268532Y-262635D01*
X269132Y-263568D01*
X269332Y-264635D01*
X269132Y-265702D01*
X268632Y-266502D01*
X267732Y-266902D01*
X265332D01*
G01X272832Y-270235D02*
X275332Y-262235D01*
X277832Y-270235D01*
G01X276932Y-267435D02*
X273732D01*
G01X281032Y-270235D02*
Y-262235D01*
X285632Y-270235D01*
Y-262235D01*
G01X293332Y-270235D02*
X289332D01*
Y-262235D01*
X293332D01*
G01X291732Y-266102D02*
X289332D01*
G01X297332Y-262235D02*
Y-270235D01*
X301332D01*
G01X304332Y-272902D02*
X310332D01*
G01X316132Y-265968D02*
X316532Y-265568D01*
X316832Y-264902D01*
X317032Y-263968D01*
X316832Y-263168D01*
X316432Y-262635D01*
X315732Y-262235D01*
X313032D01*
Y-270235D01*
X316332D01*
X317032Y-269702D01*
X317432Y-268902D01*
X317632Y-267968D01*
X317432Y-267035D01*
X316832Y-266235D01*
X316132Y-265968D01*
X313032D01*
G01X321132Y-270235D02*
Y-262235D01*
X323132D01*
X323932Y-262635D01*
X324532Y-263168D01*
X325032Y-263968D01*
X325432Y-264902D01*
X325532Y-266235D01*
X325432Y-267568D01*
X325032Y-268502D01*
X324532Y-269302D01*
X323932Y-269835D01*
X323132Y-270235D01*
X321132D01*
G01X291832Y-323235D02*
Y-315235D01*
X290632Y-316835D01*
G01Y-323235D02*
X293032D01*
G01X297932Y-319902D02*
X298632Y-318968D01*
X299232Y-318435D01*
X300032Y-318168D01*
X300732Y-318435D01*
X301232Y-318968D01*
X301632Y-319768D01*
X301732Y-320702D01*
X301632Y-321502D01*
X301232Y-322302D01*
X300632Y-322968D01*
X299932Y-323235D01*
X299132Y-322968D01*
X298432Y-322169D01*
X298032Y-320968D01*
X297932Y-319635D01*
X298132Y-317902D01*
X298432Y-316968D01*
X298932Y-316035D01*
X299632Y-315368D01*
X300332Y-315235D01*
X301032Y-315502D01*
X301532Y-316168D01*
G01X307832Y-323502D02*
X307632Y-323368D01*
Y-323102D01*
X307832Y-322968D01*
X308032Y-323102D01*
Y-323368D01*
X307832Y-323502D01*
G01X313932Y-319902D02*
X314632Y-318968D01*
X315232Y-318435D01*
X316032Y-318168D01*
X316732Y-318435D01*
X317232Y-318968D01*
X317632Y-319768D01*
X317732Y-320702D01*
X317632Y-321502D01*
X317232Y-322302D01*
X316632Y-322968D01*
X315932Y-323235D01*
X315132Y-322968D01*
X314432Y-322169D01*
X314032Y-320968D01*
X313932Y-319635D01*
X314132Y-317902D01*
X314432Y-316968D01*
X314932Y-316035D01*
X315632Y-315368D01*
X316332Y-315235D01*
X317032Y-315502D01*
X317532Y-316168D01*
G01X336832Y-323235D02*
Y-315235D01*
X335632Y-316835D01*
G01Y-323235D02*
X338032D01*
G01X344632D02*
X344832Y-321502D01*
X345132Y-320035D01*
X345532Y-318702D01*
X346032Y-317235D01*
X346832Y-315235D01*
X342832D01*
G01X352832Y-323502D02*
X352632Y-323368D01*
Y-323102D01*
X352832Y-322968D01*
X353032Y-323102D01*
Y-323368D01*
X352832Y-323502D01*
G01X358932Y-316568D02*
X359532Y-315768D01*
X360232Y-315368D01*
X361032Y-315235D01*
X362032Y-315502D01*
X362732Y-316168D01*
X362932Y-316968D01*
X362832Y-317769D01*
X362432Y-318435D01*
X360432Y-319768D01*
X359532Y-320702D01*
X358932Y-322035D01*
X358732Y-323235D01*
X362932D01*
G01X356632Y-298235D02*
Y-290235D01*
X358632D01*
X359432Y-290635D01*
X360032Y-291168D01*
X360532Y-291968D01*
X360932Y-292902D01*
X361032Y-294235D01*
X360932Y-295568D01*
X360532Y-296502D01*
X360032Y-297302D01*
X359432Y-297835D01*
X358632Y-298235D01*
X356632D01*
G54D12*
X8000Y99500D03*
Y110500D03*
X16000Y109441D03*
X12500Y117000D03*
X11500Y200000D03*
Y192000D03*
Y184000D03*
X33000Y186000D03*
X19500Y221500D03*
Y213500D03*
X59586Y40000D03*
X59500Y55000D03*
X48941Y89500D03*
X52000Y81000D03*
X59500Y95000D03*
X54059Y102500D03*
X41500Y103500D03*
X41038Y112537D03*
X41000Y213532D03*
X59075Y204000D03*
X56500Y261000D03*
X55000Y276000D03*
X81000Y8000D03*
X72555Y46921D03*
X70075Y64500D03*
X68720Y54000D03*
X81729Y77772D03*
X64075Y200000D03*
X66500Y189500D03*
X68500Y231500D03*
X69075Y247000D03*
X78937Y270653D03*
X75394Y288205D03*
X99500Y9000D03*
X91000Y18500D03*
X98000Y99000D03*
X93111Y288205D03*
X86024Y270653D03*
X93111D03*
X84843Y288205D03*
X101500Y277500D03*
X118500Y6716D03*
X113181Y31701D03*
X106954Y21716D03*
X111965Y11716D03*
X109812Y16716D03*
X117000Y122500D03*
X132000Y10500D03*
X139500D03*
X127500Y6716D03*
X134500Y105000D03*
Y119000D03*
X140000Y177500D03*
X132500Y185000D03*
X140000D03*
X132500Y192500D03*
X140000D03*
X132500Y200000D03*
X140000D03*
Y215000D03*
X132500Y207500D03*
X140000D03*
X132500Y215000D03*
X148500Y84000D03*
X147500Y177500D03*
Y200000D03*
Y185000D03*
Y192500D03*
Y222500D03*
Y215000D03*
Y207500D03*
G54D21*
X87756Y47244D03*
X109095Y89370D03*
G54D13*
X14000Y255500D03*
X60989Y131906D03*
X134016Y147928D03*
G54D22*
X101969Y52480D03*
Y68228D03*
Y60354D03*
X94882Y54449D03*
Y64291D03*
Y72165D03*
X101969Y83976D03*
Y76102D03*
G54D23*
X87756Y89370D03*
X109095Y47244D03*
G54D14*
X20315Y20079D03*
X43937D03*
G54D15*
X24016Y58661D03*
X129134Y247543D03*
G54D24*
X94882Y82008D03*
G54D16*
X25984Y279449D03*
X136221Y43425D03*
G54D25*
X339937Y104912D03*
X344937Y91728D03*
X349937Y104912D03*
X352033Y234525D03*
X342033D03*
X347033Y247709D03*
G54D17*
X57480Y26299D03*
X67480D03*
G54D26*
X350500Y420150D03*
X340500D03*
X350500Y445150D03*
X340500D03*
Y597350D03*
X350500D03*
X340500Y622350D03*
X350500D03*
X380000Y316336D03*
X370000D03*
X380000Y341336D03*
X370000D03*
Y597350D03*
X380000D03*
X370000Y622350D03*
X380000D03*
G54D18*
X77480Y26299D03*
G54D27*
X370195Y93000D03*
X380195D03*
Y247618D03*
X370195D03*
G54D28*
Y83000D03*
X380195D03*
Y257618D03*
X370195D03*
G54D19*
X64174Y294685D03*
X107874D03*
G54D29*
G01X7879Y43D02*
X146855D01*
G01X5Y7917D02*
G03X7879Y43I7874J0D01*
G01X5Y272460D02*
Y7917D01*
G01X2170Y277884D02*
G03X5Y272460I5710J-5423D01*
G01X4336Y283307D02*
G02X2170Y277884I-7874J1D01*
G01X4336Y307130D02*
Y283307D01*
G01X12210Y315004D02*
G03X4336Y307130I0J-7874D01*
G01X42721Y315004D02*
X12210D01*
G01X50595Y322878D02*
G02X42721Y315004I-7874J0D01*
G01X50595Y331342D02*
Y322878D01*
G01X58469Y339216D02*
G03X50595Y331342I0J-7874D01*
G01X113588Y339216D02*
X58469D01*
G01X121462Y322878D02*
Y331342D01*
G01X129336Y315004D02*
G02X121462Y322878I0J7874D01*
G01Y331342D02*
G03X113588Y339216I-7874J0D01*
G01X142525Y315004D02*
G02X150399Y307130I0J-7874D01*
G01Y283307D01*
G03X152564Y277884I7874J0D01*
G01X142525Y315004D02*
X129336D01*
G01X146855Y43D02*
G03X154729Y7917I0J7874D01*
G01D02*
Y272460D01*
G01D02*
G03X152564Y277884I-7875J1D01*
M02*
